# T6G (Grand Teton) — schematic netlist excerpt (pin names and nets, part order shuffled) for the footprints in the layout excerpt that follows; sources: Cadence DE-HDL packaged netlist, KiCad conversion of 04192023_DAF0TMB3IC0_F0TG_MB_C_brd_V02_OCP.brd

J116  PICOPROBE_BXA  DELTA-L 4.0 EMPTY  pkg TRIANG_LAUNCH_3PXB  page 229
  \1_p\  = DELTA_L_85_5INCH_IN5_DN
  \2_n\  = DELTA_L_85_5INCH_IN5_DP
  \3_g\  = DELTA_L_GND_1

C6616  Q_CAP_DIFFBUS  DIFF BUS_0.22UF 6.3V 20% X6S  pkg C0201  page 308 : \1\ = P5E_CPU0_P3_TX_BUF_C_DN<9> ; \2\ = P5E_CPU0_P3_TX_BUF_DN<9>

(kicad_pcb
	(version 20260206)
	(generator "pcbnew")
	(generator_version "10.0")
	(general
		(thickness 1.6)
		(legacy_teardrops no)
	)
	(paper "A4")
	(title_block
		(title "04192023_DAF0TMB3IC0_F0TG_MB_C_brd_V02_OCP.brd")
		(comment 1 "Grand Teton / footprints 6103-6104 of 8354")
	)
	(layers
		(0 "F.Cu" signal "TOP")
		(4 "In1.Cu" signal "GND")
		(6 "In2.Cu" signal "IN1")
		(8 "In3.Cu" signal "GND1")
		(10 "In4.Cu" signal "IN2")
		(12 "In5.Cu" signal "GND2")
		(14 "In6.Cu" signal "IN3")
		(16 "In7.Cu" signal "GND3")
		(18 "In8.Cu" signal "VCC")
		(20 "In9.Cu" signal "VCC1")
		(22 "In10.Cu" signal "GND4")
		(24 "In11.Cu" signal "IN4")
		(26 "In12.Cu" signal "GND5")
		(28 "In13.Cu" signal "IN5")
		(30 "In14.Cu" signal "GND6")
		(32 "In15.Cu" signal "IN6")
		(34 "In16.Cu" signal "GND7")
		(2 "B.Cu" signal "BOTTOM")
		(9 "F.Adhes" user "F.Adhesive")
		(11 "B.Adhes" user "B.Adhesive")
		(13 "F.Paste" user "Package Geometry/Pastemask Top")
		(15 "B.Paste" user "Package Geometry/Pastemask Bottom")
		(5 "F.SilkS" user "Ref Des/Silkscreen Top")
		(7 "B.SilkS" user "Ref Des/Silkscreen Bottom")
		(1 "F.Mask" user "Board Geometry/Soldermask Top")
		(3 "B.Mask" user "Board Geometry/Soldermask Bottom")
		(17 "Dwgs.User" user "User.Drawings")
		(19 "Cmts.User" user "User.Comments")
		(21 "Eco1.User" user "User.Eco1")
		(23 "Eco2.User" user "User.Eco2")
		(25 "Edge.Cuts" user "Board Geometry/Outline")
		(27 "Margin" user)
		(31 "F.CrtYd" user "Package Geometry/Place Bound Top")
		(29 "B.CrtYd" user "Package Geometry/Place Bound Bottom")
		(35 "F.Fab" user "Ref Des/Assembly Top")
		(33 "B.Fab" user "Ref Des/Assembly Bottom")
	)
	(footprint ""
		(layer "B.Cu")
		(at 366.288574 7.622794)
		(property "Reference" "J116"
			(at 4.461002 1.607058 270)
			(unlocked yes)
			(layer "B.SilkS")
			(effects
				(font
					(size 0.7874 0.5842)
					(thickness 0.1524)
				)
				(justify left mirror)
			)
		)
		(property "Value" ""
			(at 0 0 0)
			(layer "B.Fab")
			(effects
				(font
					(size 1.27 1.27)
				)
				(justify mirror)
			)
		)
		(duplicate_pad_numbers_are_jumpers no)
		(fp_line
			(start -1.2192 -2.06756)
			(end -1.2192 2.06756)
			(stroke
				(width 0.1524)
				(type default)
			)
			(layer "B.SilkS")
		)
		(fp_line
			(start -1.2192 2.06756)
			(end 1.2192 2.06756)
			(stroke
				(width 0.1524)
				(type default)
			)
			(layer "B.SilkS")
		)
		(fp_line
			(start 1.2192 -2.06756)
			(end -1.2192 -2.06756)
			(stroke
				(width 0.1524)
				(type default)
			)
			(layer "B.SilkS")
		)
		(fp_line
			(start 1.2192 2.06756)
			(end 1.2192 -2.06756)
			(stroke
				(width 0.1524)
				(type default)
			)
			(layer "B.SilkS")
		)
		(pad "" np_thru_hole circle
			(at -3.4671 -1.27 270)
			(size 1.0414 1.0414)
			(drill 1.0414)
			(layers "*.Cu" "*.Mask")
			(clearance 0.381)
			(thermal_gap 0.381)
		)
		(pad "" np_thru_hole circle
			(at -3.4671 1.27 270)
			(size 1.0414 1.0414)
			(drill 1.0414)
			(layers "*.Cu" "*.Mask")
			(clearance 0.381)
			(thermal_gap 0.381)
		)
		(pad "" np_thru_hole circle
			(at 2.8829 -1.27 270)
			(size 1.0414 1.0414)
			(drill 1.0414)
			(layers "*.Cu" "*.Mask")
			(clearance 0.381)
			(thermal_gap 0.381)
		)
		(pad "" np_thru_hole circle
			(at 2.8829 1.27 270)
			(size 1.0414 1.0414)
			(drill 1.0414)
			(layers "*.Cu" "*.Mask")
			(clearance 0.381)
			(thermal_gap 0.381)
		)
		(pad "1" smd rect
			(at -0.8255 -0.249936 270)
			(size 0.3048 0.508)
			(layers "B.Cu" "B.Mask" "B.Paste")
			(net "DELTA_L_85_5INCH_IN5_DN")
		)
		(pad "2" smd rect
			(at -0.8255 0.249936 270)
			(size 0.3048 0.508)
			(layers "B.Cu" "B.Mask" "B.Paste")
			(net "DELTA_L_85_5INCH_IN5_DP")
		)
		(pad "3" smd circle
			(at 0 0 180)
			(size 0 0)
			(layers "B.Cu" "B.Mask" "B.Paste")
			(net "DELTA_L_GND_1")
		)
		(zone
			(layers "F.Cu" "B.Cu" "In1.Cu" "In2.Cu" "In3.Cu" "In4.Cu" "In5.Cu" "In6.Cu"
				"In7.Cu" "In8.Cu" "In9.Cu" "In10.Cu" "In11.Cu" "In12.Cu" "In13.Cu" "In14.Cu"
				"In15.Cu" "In16.Cu"
			)
			(hatch none 0.5)
			(connect_pads
				(clearance 0)
			)
			(min_thickness 0.25)
			(keepout
				(tracks not_allowed)
				(vias allowed)
				(pads allowed)
				(copperpour not_allowed)
				(footprints allowed)
			)
			(placement
				(enabled no)
				(sheetname "")
			)
			(fill
				(thermal_gap 0.5)
				(thermal_bridge_width 0.5)
				(island_removal_mode 0)
			)
			(polygon
				(pts
					(arc
						(start 363.748574 6.352794)
						(mid 361.894374 6.352794)
						(end 363.748574 6.352794)
					)
				)
			)
		)
		(zone
			(layers "F.Cu" "B.Cu" "In1.Cu" "In2.Cu" "In3.Cu" "In4.Cu" "In5.Cu" "In6.Cu"
				"In7.Cu" "In8.Cu" "In9.Cu" "In10.Cu" "In11.Cu" "In12.Cu" "In13.Cu" "In14.Cu"
				"In15.Cu" "In16.Cu"
			)
			(hatch none 0.5)
			(connect_pads
				(clearance 0)
			)
			(min_thickness 0.25)
			(keepout
				(tracks not_allowed)
				(vias allowed)
				(pads allowed)
				(copperpour not_allowed)
				(footprints allowed)
			)
			(placement
				(enabled no)
				(sheetname "")
			)
			(fill
				(thermal_gap 0.5)
				(thermal_bridge_width 0.5)
				(island_removal_mode 0)
			)
			(polygon
				(pts
					(arc
						(start 363.748574 8.892794)
						(mid 361.894374 8.892794)
						(end 363.748574 8.892794)
					)
				)
			)
		)
		(zone
			(layers "F.Cu" "B.Cu" "In1.Cu" "In2.Cu" "In3.Cu" "In4.Cu" "In5.Cu" "In6.Cu"
				"In7.Cu" "In8.Cu" "In9.Cu" "In10.Cu" "In11.Cu" "In12.Cu" "In13.Cu" "In14.Cu"
				"In15.Cu" "In16.Cu"
			)
			(hatch none 0.5)
			(connect_pads
				(clearance 0)
			)
			(min_thickness 0.25)
			(keepout
				(tracks not_allowed)
				(vias allowed)
				(pads allowed)
				(copperpour not_allowed)
				(footprints allowed)
			)
			(placement
				(enabled no)
				(sheetname "")
			)
			(fill
				(thermal_gap 0.5)
				(thermal_bridge_width 0.5)
				(island_removal_mode 0)
			)
			(polygon
				(pts
					(arc
						(start 370.098574 6.352794)
						(mid 368.244374 6.352794)
						(end 370.098574 6.352794)
					)
				)
			)
		)
		(zone
			(layers "F.Cu" "B.Cu" "In1.Cu" "In2.Cu" "In3.Cu" "In4.Cu" "In5.Cu" "In6.Cu"
				"In7.Cu" "In8.Cu" "In9.Cu" "In10.Cu" "In11.Cu" "In12.Cu" "In13.Cu" "In14.Cu"
				"In15.Cu" "In16.Cu"
			)
			(hatch none 0.5)
			(connect_pads
				(clearance 0)
			)
			(min_thickness 0.25)
			(keepout
				(tracks not_allowed)
				(vias allowed)
				(pads allowed)
				(copperpour not_allowed)
				(footprints allowed)
			)
			(placement
				(enabled no)
				(sheetname "")
			)
			(fill
				(thermal_gap 0.5)
				(thermal_bridge_width 0.5)
				(island_removal_mode 0)
			)
			(polygon
				(pts
					(arc
						(start 370.098574 8.892794)
						(mid 368.244374 8.892794)
						(end 370.098574 8.892794)
					)
				)
			)
		)
		(zone
			(layer "B.Cu")
			(hatch none 0.5)
			(connect_pads
				(clearance 0)
			)
			(min_thickness 0.25)
			(keepout
				(tracks not_allowed)
				(vias allowed)
				(pads allowed)
				(copperpour not_allowed)
				(footprints allowed)
			)
			(placement
				(enabled no)
				(sheetname "")
			)
			(fill
				(thermal_gap 0.5)
				(thermal_bridge_width 0.5)
				(island_removal_mode 0)
			)
			(polygon
				(pts
					(xy 365.170974 7.074154) (xy 365.170974 7.169658) (xy 365.767874 7.169658) (xy 365.767874 7.576058)
					(xy 365.170974 7.576058) (xy 365.170974 7.66953) (xy 365.767874 7.66953) (xy 365.767874 8.07593)
					(xy 365.170974 8.07593) (xy 365.170974 8.171434) (xy 365.869474 8.171434) (xy 365.869474 7.074154)
				)
			)
		)
	)
	(footprint ""
		(layer "B.Cu")
		(at 399.969482 -416.899344 90)
		(property "Reference" "C6616"
			(at 0 0 90)
			(layer "B.SilkS")
			(hide yes)
			(effects
				(font
					(size 1.27 1.27)
				)
				(justify mirror)
			)
		)
		(property "Value" ""
			(at 0 0 90)
			(layer "B.Fab")
			(effects
				(font
					(size 1.27 1.27)
				)
				(justify mirror)
			)
		)
		(duplicate_pad_numbers_are_jumpers no)
		(fp_line
			(start 0.299974 -0.150114)
			(end -0.299974 -0.150114)
			(stroke
				(width 0.1)
				(type default)
			)
			(layer "B.Fab")
		)
		(fp_line
			(start -0.299974 -0.150114)
			(end -0.299974 0.150114)
			(stroke
				(width 0.1)
				(type default)
			)
			(layer "B.Fab")
		)
		(fp_line
			(start 0.299974 0.150114)
			(end 0.299974 -0.150114)
			(stroke
				(width 0.1)
				(type default)
			)
			(layer "B.Fab")
		)
		(fp_line
			(start -0.299974 0.150114)
			(end 0.299974 0.150114)
			(stroke
				(width 0.1)
				(type default)
			)
			(layer "B.Fab")
		)
		(pad "1" smd rect
			(at 0.2667 0 270)
			(size 0.3048 0.381)
			(layers "B.Cu" "B.Mask" "B.Paste")
			(net "P5E_CPU0_P3_TX_BUF_C_DN<9>")
		)
		(pad "2" smd rect
			(at -0.2667 0 270)
			(size 0.3048 0.381)
			(layers "B.Cu" "B.Mask" "B.Paste")
			(net "P5E_CPU0_P3_TX_BUF_DN<9>")
		)
	)
)
